(kicad_pcb
	(version 20260206)
	(generator "pcbnew")
	(generator_version "10.0")
	(general
		(thickness 1.6)
		(legacy_teardrops no)
	)
	(paper "A4")
	(title_block
		(title "04192023_DAF0TMB3IC0_F0TG_MB_C_brd_V02_OCP.brd")
		(comment 1 "Grand Teton / footprints 4211-4218 of 8354")
	)
	(layers
		(0 "F.Cu" signal "TOP")
		(4 "In1.Cu" signal "GND")
		(6 "In2.Cu" signal "IN1")
		(8 "In3.Cu" signal "GND1")
		(10 "In4.Cu" signal "IN2")
		(12 "In5.Cu" signal "GND2")
		(14 "In6.Cu" signal "IN3")
		(16 "In7.Cu" signal "GND3")
		(18 "In8.Cu" signal "VCC")
		(20 "In9.Cu" signal "VCC1")
		(22 "In10.Cu" signal "GND4")
		(24 "In11.Cu" signal "IN4")
		(26 "In12.Cu" signal "GND5")
		(28 "In13.Cu" signal "IN5")
		(30 "In14.Cu" signal "GND6")
		(32 "In15.Cu" signal "IN6")
		(34 "In16.Cu" signal "GND7")
		(2 "B.Cu" signal "BOTTOM")
		(9 "F.Adhes" user "F.Adhesive")
		(11 "B.Adhes" user "B.Adhesive")
		(13 "F.Paste" user "Package Geometry/Pastemask Top")
		(15 "B.Paste" user "Package Geometry/Pastemask Bottom")
		(5 "F.SilkS" user "Ref Des/Silkscreen Top")
		(7 "B.SilkS" user "Ref Des/Silkscreen Bottom")
		(1 "F.Mask" user "Board Geometry/Soldermask Top")
		(3 "B.Mask" user "Board Geometry/Soldermask Bottom")
		(17 "Dwgs.User" user "User.Drawings")
		(19 "Cmts.User" user "User.Comments")
		(21 "Eco1.User" user "User.Eco1")
		(23 "Eco2.User" user "User.Eco2")
		(25 "Edge.Cuts" user "Board Geometry/Outline")
		(27 "Margin" user)
		(31 "F.CrtYd" user "Package Geometry/Place Bound Top")
		(29 "B.CrtYd" user "Package Geometry/Place Bound Bottom")
		(35 "F.Fab" user "Ref Des/Assembly Top")
		(33 "B.Fab" user "Ref Des/Assembly Bottom")
	)
	(footprint ""
		(layer "F.Cu")
		(at 178.689 -395.351 180)
		(property "Reference" "PR3929"
			(at 0 0 180)
			(layer "F.SilkS")
			(hide yes)
			(effects
				(font
					(size 1.27 1.27)
				)
			)
		)
		(property "Value" ""
			(at 0 0 180)
			(layer "F.Fab")
			(effects
				(font
					(size 1.27 1.27)
				)
			)
		)
		(duplicate_pad_numbers_are_jumpers no)
		(fp_line
			(start 0.7874 0.4064)
			(end -0.7874 0.4064)
			(stroke
				(width 0.1524)
				(type default)
			)
			(layer "F.SilkS")
		)
		(fp_line
			(start 0.7874 -0.4064)
			(end 0.7874 0.4064)
			(stroke
				(width 0.1524)
				(type default)
			)
			(layer "F.SilkS")
		)
		(fp_line
			(start -0.7874 0.4064)
			(end -0.7874 -0.4064)
			(stroke
				(width 0.1524)
				(type default)
			)
			(layer "F.SilkS")
		)
		(fp_line
			(start -0.7874 -0.4064)
			(end 0.7874 -0.4064)
			(stroke
				(width 0.1524)
				(type default)
			)
			(layer "F.SilkS")
		)
		(fp_line
			(start 0.67945 0.3048)
			(end 0.120396 0.3048)
			(stroke
				(width 0.1)
				(type default)
			)
			(layer "F.Fab")
		)
		(fp_line
			(start 0.67945 -0.3048)
			(end 0.67945 0.3048)
			(stroke
				(width 0.1)
				(type default)
			)
			(layer "F.Fab")
		)
		(fp_line
			(start 0.12065 -0.2794)
			(end 0.12065 -0.3048)
			(stroke
				(width 0.1)
				(type default)
			)
			(layer "F.Fab")
		)
		(fp_line
			(start 0.12065 -0.3048)
			(end 0.67945 -0.3048)
			(stroke
				(width 0.1)
				(type default)
			)
			(layer "F.Fab")
		)
		(fp_line
			(start 0.120396 0.3048)
			(end 0.120396 0.2794)
			(stroke
				(width 0.1)
				(type default)
			)
			(layer "F.Fab")
		)
		(fp_line
			(start 0.120396 0.2794)
			(end -0.12065 0.2794)
			(stroke
				(width 0.1)
				(type default)
			)
			(layer "F.Fab")
		)
		(fp_line
			(start -0.12065 0.3048)
			(end -0.67945 0.3048)
			(stroke
				(width 0.1)
				(type default)
			)
			(layer "F.Fab")
		)
		(fp_line
			(start -0.12065 0.2794)
			(end -0.12065 0.3048)
			(stroke
				(width 0.1)
				(type default)
			)
			(layer "F.Fab")
		)
		(fp_line
			(start -0.12065 -0.2794)
			(end 0.12065 -0.2794)
			(stroke
				(width 0.1)
				(type default)
			)
			(layer "F.Fab")
		)
		(fp_line
			(start -0.12065 -0.305054)
			(end -0.12065 -0.2794)
			(stroke
				(width 0.1)
				(type default)
			)
			(layer "F.Fab")
		)
		(fp_line
			(start -0.67945 0.3048)
			(end -0.67945 -0.305054)
			(stroke
				(width 0.1)
				(type default)
			)
			(layer "F.Fab")
		)
		(fp_line
			(start -0.67945 -0.305054)
			(end -0.12065 -0.305054)
			(stroke
				(width 0.1)
				(type default)
			)
			(layer "F.Fab")
		)
		(pad "1" smd circle
			(at -0.40005 0 180)
			(size 0 0)
			(layers "F.Cu" "F.Mask" "F.Paste")
			(net "HSC_ADDR")
		)
		(pad "2" smd circle
			(at 0.40005 0 180)
			(size 0 0)
			(layers "F.Cu" "F.Mask" "F.Paste")
			(net "HSC_VDD18")
		)
	)
	(footprint ""
		(layer "F.Cu")
		(at 126.320296 -370.57203 -90)
		(property "Reference" "C1528"
			(at 0 0 270)
			(layer "F.SilkS")
			(hide yes)
			(effects
				(font
					(size 1.27 1.27)
				)
			)
		)
		(property "Value" ""
			(at 0 0 270)
			(layer "F.Fab")
			(effects
				(font
					(size 1.27 1.27)
				)
			)
		)
		(duplicate_pad_numbers_are_jumpers no)
		(fp_line
			(start -0.299974 0.150114)
			(end -0.299974 -0.150114)
			(stroke
				(width 0.1)
				(type default)
			)
			(layer "F.Fab")
		)
		(fp_line
			(start 0.299974 0.150114)
			(end -0.299974 0.150114)
			(stroke
				(width 0.1)
				(type default)
			)
			(layer "F.Fab")
		)
		(fp_line
			(start -0.299974 -0.150114)
			(end 0.299974 -0.150114)
			(stroke
				(width 0.1)
				(type default)
			)
			(layer "F.Fab")
		)
		(fp_line
			(start 0.299974 -0.150114)
			(end 0.299974 0.150114)
			(stroke
				(width 0.1)
				(type default)
			)
			(layer "F.Fab")
		)
		(pad "1" smd rect
			(at -0.2667 0 270)
			(size 0.3048 0.381)
			(layers "F.Cu" "F.Mask" "F.Paste")
			(net "P5E_CPU1_P3_TX_C_DN<9>")
		)
		(pad "2" smd rect
			(at 0.2667 0 270)
			(size 0.3048 0.381)
			(layers "F.Cu" "F.Mask" "F.Paste")
			(net "P5E_CPU1_P3_TX_DN<9>")
		)
	)
	(footprint ""
		(layer "F.Cu")
		(at 45.932344 -421.326564)
		(property "Reference" "R1467"
			(at 0 0 0)
			(layer "F.SilkS")
			(hide yes)
			(effects
				(font
					(size 1.27 1.27)
				)
			)
		)
		(property "Value" ""
			(at 0 0 0)
			(layer "F.Fab")
			(effects
				(font
					(size 1.27 1.27)
				)
			)
		)
		(duplicate_pad_numbers_are_jumpers no)
		(fp_line
			(start -0.32512 -0.175006)
			(end 0.32512 -0.175006)
			(stroke
				(width 0.1)
				(type default)
			)
			(layer "F.Fab")
		)
		(fp_line
			(start -0.32512 0.175006)
			(end -0.32512 -0.175006)
			(stroke
				(width 0.1)
				(type default)
			)
			(layer "F.Fab")
		)
		(fp_line
			(start 0.32512 -0.175006)
			(end 0.32512 0.175006)
			(stroke
				(width 0.1)
				(type default)
			)
			(layer "F.Fab")
		)
		(fp_line
			(start 0.32512 0.175006)
			(end -0.32512 0.175006)
			(stroke
				(width 0.1)
				(type default)
			)
			(layer "F.Fab")
		)
		(pad "1" smd rect
			(at -0.2667 0)
			(size 0.3048 0.381)
			(layers "F.Cu" "F.Mask" "F.Paste")
			(net "P1V8_CPU1_RT_1D")
		)
		(pad "2" smd rect
			(at 0.2667 0 180)
			(size 0.3048 0.381)
			(layers "F.Cu" "F.Mask" "F.Paste")
			(net "JTAG_TCK_RT_CPU1_P0")
		)
	)
	(footprint ""
		(layer "F.Cu")
		(at 173.216062 -30.446472 180)
		(property "Reference" "PR4007"
			(at 0 0 180)
			(layer "F.SilkS")
			(hide yes)
			(effects
				(font
					(size 1.27 1.27)
				)
			)
		)
		(property "Value" ""
			(at 0 0 180)
			(layer "F.Fab")
			(effects
				(font
					(size 1.27 1.27)
				)
			)
		)
		(duplicate_pad_numbers_are_jumpers no)
		(fp_line
			(start 0.7874 0.4064)
			(end -0.7874 0.4064)
			(stroke
				(width 0.1524)
				(type default)
			)
			(layer "F.SilkS")
		)
		(fp_line
			(start 0.7874 -0.4064)
			(end 0.7874 0.4064)
			(stroke
				(width 0.1524)
				(type default)
			)
			(layer "F.SilkS")
		)
		(fp_line
			(start -0.7874 0.4064)
			(end -0.7874 -0.4064)
			(stroke
				(width 0.1524)
				(type default)
			)
			(layer "F.SilkS")
		)
		(fp_line
			(start -0.7874 -0.4064)
			(end 0.7874 -0.4064)
			(stroke
				(width 0.1524)
				(type default)
			)
			(layer "F.SilkS")
		)
		(fp_line
			(start 0.67945 0.3048)
			(end 0.120396 0.3048)
			(stroke
				(width 0.1)
				(type default)
			)
			(layer "F.Fab")
		)
		(fp_line
			(start 0.67945 -0.3048)
			(end 0.67945 0.3048)
			(stroke
				(width 0.1)
				(type default)
			)
			(layer "F.Fab")
		)
		(fp_line
			(start 0.12065 -0.2794)
			(end 0.12065 -0.3048)
			(stroke
				(width 0.1)
				(type default)
			)
			(layer "F.Fab")
		)
		(fp_line
			(start 0.12065 -0.3048)
			(end 0.67945 -0.3048)
			(stroke
				(width 0.1)
				(type default)
			)
			(layer "F.Fab")
		)
		(fp_line
			(start 0.120396 0.3048)
			(end 0.120396 0.2794)
			(stroke
				(width 0.1)
				(type default)
			)
			(layer "F.Fab")
		)
		(fp_line
			(start 0.120396 0.2794)
			(end -0.12065 0.2794)
			(stroke
				(width 0.1)
				(type default)
			)
			(layer "F.Fab")
		)
		(fp_line
			(start -0.12065 0.3048)
			(end -0.67945 0.3048)
			(stroke
				(width 0.1)
				(type default)
			)
			(layer "F.Fab")
		)
		(fp_line
			(start -0.12065 0.2794)
			(end -0.12065 0.3048)
			(stroke
				(width 0.1)
				(type default)
			)
			(layer "F.Fab")
		)
		(fp_line
			(start -0.12065 -0.2794)
			(end 0.12065 -0.2794)
			(stroke
				(width 0.1)
				(type default)
			)
			(layer "F.Fab")
		)
		(fp_line
			(start -0.12065 -0.305054)
			(end -0.12065 -0.2794)
			(stroke
				(width 0.1)
				(type default)
			)
			(layer "F.Fab")
		)
		(fp_line
			(start -0.67945 0.3048)
			(end -0.67945 -0.305054)
			(stroke
				(width 0.1)
				(type default)
			)
			(layer "F.Fab")
		)
		(fp_line
			(start -0.67945 -0.305054)
			(end -0.12065 -0.305054)
			(stroke
				(width 0.1)
				(type default)
			)
			(layer "F.Fab")
		)
		(pad "1" smd circle
			(at -0.40005 0 180)
			(size 0 0)
			(layers "F.Cu" "F.Mask" "F.Paste")
			(net "P12V_SCM_FLTB_N")
		)
		(pad "2" smd circle
			(at 0.40005 0 180)
			(size 0 0)
			(layers "F.Cu" "F.Mask" "F.Paste")
			(net "P3V3_AUX")
		)
	)
	(footprint ""
		(layer "F.Cu")
		(at 448.671442 -415.464244 180)
		(property "Reference" "PC6562"
			(at 0 0 180)
			(layer "F.SilkS")
			(hide yes)
			(effects
				(font
					(size 1.27 1.27)
				)
			)
		)
		(property "Value" ""
			(at 0 0 180)
			(layer "F.Fab")
			(effects
				(font
					(size 1.27 1.27)
				)
			)
		)
		(duplicate_pad_numbers_are_jumpers no)
		(fp_line
			(start 0.7874 0.4064)
			(end -0.7874 0.4064)
			(stroke
				(width 0.1524)
				(type default)
			)
			(layer "F.SilkS")
		)
		(fp_line
			(start 0.7874 -0.4064)
			(end 0.7874 0.4064)
			(stroke
				(width 0.1524)
				(type default)
			)
			(layer "F.SilkS")
		)
		(fp_line
			(start -0.7874 0.4064)
			(end -0.7874 -0.4064)
			(stroke
				(width 0.1524)
				(type default)
			)
			(layer "F.SilkS")
		)
		(fp_line
			(start -0.7874 -0.4064)
			(end 0.7874 -0.4064)
			(stroke
				(width 0.1524)
				(type default)
			)
			(layer "F.SilkS")
		)
		(fp_line
			(start 0.67945 0.3048)
			(end 0.120396 0.3048)
			(stroke
				(width 0.1)
				(type default)
			)
			(layer "F.Fab")
		)
		(fp_line
			(start 0.67945 -0.3048)
			(end 0.67945 0.3048)
			(stroke
				(width 0.1)
				(type default)
			)
			(layer "F.Fab")
		)
		(fp_line
			(start 0.12065 -0.2794)
			(end 0.12065 -0.3048)
			(stroke
				(width 0.1)
				(type default)
			)
			(layer "F.Fab")
		)
		(fp_line
			(start 0.12065 -0.3048)
			(end 0.67945 -0.3048)
			(stroke
				(width 0.1)
				(type default)
			)
			(layer "F.Fab")
		)
		(fp_line
			(start 0.120396 0.3048)
			(end 0.120396 0.2794)
			(stroke
				(width 0.1)
				(type default)
			)
			(layer "F.Fab")
		)
		(fp_line
			(start 0.120396 0.2794)
			(end -0.12065 0.2794)
			(stroke
				(width 0.1)
				(type default)
			)
			(layer "F.Fab")
		)
		(fp_line
			(start -0.12065 0.3048)
			(end -0.67945 0.3048)
			(stroke
				(width 0.1)
				(type default)
			)
			(layer "F.Fab")
		)
		(fp_line
			(start -0.12065 0.2794)
			(end -0.12065 0.3048)
			(stroke
				(width 0.1)
				(type default)
			)
			(layer "F.Fab")
		)
		(fp_line
			(start -0.12065 -0.2794)
			(end 0.12065 -0.2794)
			(stroke
				(width 0.1)
				(type default)
			)
			(layer "F.Fab")
		)
		(fp_line
			(start -0.12065 -0.305054)
			(end -0.12065 -0.2794)
			(stroke
				(width 0.1)
				(type default)
			)
			(layer "F.Fab")
		)
		(fp_line
			(start -0.67945 0.3048)
			(end -0.67945 -0.305054)
			(stroke
				(width 0.1)
				(type default)
			)
			(layer "F.Fab")
		)
		(fp_line
			(start -0.67945 -0.305054)
			(end -0.12065 -0.305054)
			(stroke
				(width 0.1)
				(type default)
			)
			(layer "F.Fab")
		)
		(pad "1" smd circle
			(at -0.40005 0 180)
			(size 0 0)
			(layers "F.Cu" "F.Mask" "F.Paste")
			(net "P12V_AUX")
		)
		(pad "2" smd circle
			(at 0.40005 0 180)
			(size 0 0)
			(layers "F.Cu" "F.Mask" "F.Paste")
			(net "GND")
		)
	)
	(footprint ""
		(layer "F.Cu")
		(at 172.230034 -332.788006 -90)
		(property "Reference" "PC524"
			(at 0 0 270)
			(layer "F.SilkS")
			(hide yes)
			(effects
				(font
					(size 1.27 1.27)
				)
			)
		)
		(property "Value" ""
			(at 0 0 270)
			(layer "F.Fab")
			(effects
				(font
					(size 1.27 1.27)
				)
			)
		)
		(duplicate_pad_numbers_are_jumpers no)
		(fp_line
			(start -0.7874 0.4064)
			(end -0.7874 -0.4064)
			(stroke
				(width 0.1524)
				(type default)
			)
			(layer "F.SilkS")
		)
		(fp_line
			(start 0.7874 0.4064)
			(end -0.7874 0.4064)
			(stroke
				(width 0.1524)
				(type default)
			)
			(layer "F.SilkS")
		)
		(fp_line
			(start -0.7874 -0.4064)
			(end 0.7874 -0.4064)
			(stroke
				(width 0.1524)
				(type default)
			)
			(layer "F.SilkS")
		)
		(fp_line
			(start 0.7874 -0.4064)
			(end 0.7874 0.4064)
			(stroke
				(width 0.1524)
				(type default)
			)
			(layer "F.SilkS")
		)
		(fp_line
			(start -0.67945 0.3048)
			(end -0.67945 -0.305054)
			(stroke
				(width 0.1)
				(type default)
			)
			(layer "F.Fab")
		)
		(fp_line
			(start -0.12065 0.3048)
			(end -0.67945 0.3048)
			(stroke
				(width 0.1)
				(type default)
			)
			(layer "F.Fab")
		)
		(fp_line
			(start 0.120396 0.3048)
			(end 0.120396 0.2794)
			(stroke
				(width 0.1)
				(type default)
			)
			(layer "F.Fab")
		)
		(fp_line
			(start 0.67945 0.3048)
			(end 0.120396 0.3048)
			(stroke
				(width 0.1)
				(type default)
			)
			(layer "F.Fab")
		)
		(fp_line
			(start -0.12065 0.2794)
			(end -0.12065 0.3048)
			(stroke
				(width 0.1)
				(type default)
			)
			(layer "F.Fab")
		)
		(fp_line
			(start 0.120396 0.2794)
			(end -0.12065 0.2794)
			(stroke
				(width 0.1)
				(type default)
			)
			(layer "F.Fab")
		)
		(fp_line
			(start -0.12065 -0.2794)
			(end 0.12065 -0.2794)
			(stroke
				(width 0.1)
				(type default)
			)
			(layer "F.Fab")
		)
		(fp_line
			(start 0.12065 -0.2794)
			(end 0.12065 -0.3048)
			(stroke
				(width 0.1)
				(type default)
			)
			(layer "F.Fab")
		)
		(fp_line
			(start 0.12065 -0.3048)
			(end 0.67945 -0.3048)
			(stroke
				(width 0.1)
				(type default)
			)
			(layer "F.Fab")
		)
		(fp_line
			(start 0.67945 -0.3048)
			(end 0.67945 0.3048)
			(stroke
				(width 0.1)
				(type default)
			)
			(layer "F.Fab")
		)
		(fp_line
			(start -0.67945 -0.305054)
			(end -0.12065 -0.305054)
			(stroke
				(width 0.1)
				(type default)
			)
			(layer "F.Fab")
		)
		(fp_line
			(start -0.12065 -0.305054)
			(end -0.12065 -0.2794)
			(stroke
				(width 0.1)
				(type default)
			)
			(layer "F.Fab")
		)
		(pad "1" smd circle
			(at -0.40005 0 270)
			(size 0 0)
			(layers "F.Cu" "F.Mask" "F.Paste")
			(net "PVDD11_S3_P1")
		)
		(pad "2" smd circle
			(at 0.40005 0 270)
			(size 0 0)
			(layers "F.Cu" "F.Mask" "F.Paste")
			(net "GND")
		)
	)
	(footprint ""
		(layer "F.Cu")
		(at 168.60901 -394.3604 -90)
		(property "Reference" "R6796"
			(at 0 0 270)
			(layer "F.SilkS")
			(hide yes)
			(effects
				(font
					(size 1.27 1.27)
				)
			)
		)
		(property "Value" ""
			(at 0 0 270)
			(layer "F.Fab")
			(effects
				(font
					(size 1.27 1.27)
				)
			)
		)
		(duplicate_pad_numbers_are_jumpers no)
		(fp_line
			(start -0.32512 0.175006)
			(end -0.32512 -0.175006)
			(stroke
				(width 0.1)
				(type default)
			)
			(layer "F.Fab")
		)
		(fp_line
			(start 0.32512 0.175006)
			(end -0.32512 0.175006)
			(stroke
				(width 0.1)
				(type default)
			)
			(layer "F.Fab")
		)
		(fp_line
			(start -0.32512 -0.175006)
			(end 0.32512 -0.175006)
			(stroke
				(width 0.1)
				(type default)
			)
			(layer "F.Fab")
		)
		(fp_line
			(start 0.32512 -0.175006)
			(end 0.32512 0.175006)
			(stroke
				(width 0.1)
				(type default)
			)
			(layer "F.Fab")
		)
		(pad "1" smd rect
			(at -0.2667 0 270)
			(size 0.3048 0.381)
			(layers "F.Cu" "F.Mask" "F.Paste")
			(net "NCF_A1_CPU1_P2_GND")
		)
		(pad "2" smd rect
			(at 0.2667 0 90)
			(size 0.3048 0.381)
			(layers "F.Cu" "F.Mask" "F.Paste")
			(net "GND")
		)
	)
	(footprint ""
		(layer "F.Cu")
		(at 256.889504 -43.504612 180)
		(property "Reference" "PR3966"
			(at 0 0 180)
			(layer "F.SilkS")
			(hide yes)
			(effects
				(font
					(size 1.27 1.27)
				)
			)
		)
		(property "Value" ""
			(at 0 0 180)
			(layer "F.Fab")
			(effects
				(font
					(size 1.27 1.27)
				)
			)
		)
		(duplicate_pad_numbers_are_jumpers no)
		(fp_line
			(start 0.7874 0.4064)
			(end -0.7874 0.4064)
			(stroke
				(width 0.1524)
				(type default)
			)
			(layer "F.SilkS")
		)
		(fp_line
			(start 0.7874 -0.4064)
			(end 0.7874 0.4064)
			(stroke
				(width 0.1524)
				(type default)
			)
			(layer "F.SilkS")
		)
		(fp_line
			(start -0.7874 0.4064)
			(end -0.7874 -0.4064)
			(stroke
				(width 0.1524)
				(type default)
			)
			(layer "F.SilkS")
		)
		(fp_line
			(start -0.7874 -0.4064)
			(end 0.7874 -0.4064)
			(stroke
				(width 0.1524)
				(type default)
			)
			(layer "F.SilkS")
		)
		(fp_line
			(start 0.67945 0.3048)
			(end 0.120396 0.3048)
			(stroke
				(width 0.1)
				(type default)
			)
			(layer "F.Fab")
		)
		(fp_line
			(start 0.67945 -0.3048)
			(end 0.67945 0.3048)
			(stroke
				(width 0.1)
				(type default)
			)
			(layer "F.Fab")
		)
		(fp_line
			(start 0.12065 -0.2794)
			(end 0.12065 -0.3048)
			(stroke
				(width 0.1)
				(type default)
			)
			(layer "F.Fab")
		)
		(fp_line
			(start 0.12065 -0.3048)
			(end 0.67945 -0.3048)
			(stroke
				(width 0.1)
				(type default)
			)
			(layer "F.Fab")
		)
		(fp_line
			(start 0.120396 0.3048)
			(end 0.120396 0.2794)
			(stroke
				(width 0.1)
				(type default)
			)
			(layer "F.Fab")
		)
		(fp_line
			(start 0.120396 0.2794)
			(end -0.12065 0.2794)
			(stroke
				(width 0.1)
				(type default)
			)
			(layer "F.Fab")
		)
		(fp_line
			(start -0.12065 0.3048)
			(end -0.67945 0.3048)
			(stroke
				(width 0.1)
				(type default)
			)
			(layer "F.Fab")
		)
		(fp_line
			(start -0.12065 0.2794)
			(end -0.12065 0.3048)
			(stroke
				(width 0.1)
				(type default)
			)
			(layer "F.Fab")
		)
		(fp_line
			(start -0.12065 -0.2794)
			(end 0.12065 -0.2794)
			(stroke
				(width 0.1)
				(type default)
			)
			(layer "F.Fab")
		)
		(fp_line
			(start -0.12065 -0.305054)
			(end -0.12065 -0.2794)
			(stroke
				(width 0.1)
				(type default)
			)
			(layer "F.Fab")
		)
		(fp_line
			(start -0.67945 0.3048)
			(end -0.67945 -0.305054)
			(stroke
				(width 0.1)
				(type default)
			)
			(layer "F.Fab")
		)
		(fp_line
			(start -0.67945 -0.305054)
			(end -0.12065 -0.305054)
			(stroke
				(width 0.1)
				(type default)
			)
			(layer "F.Fab")
		)
		(pad "1" smd circle
			(at -0.40005 0 180)
			(size 0 0)
			(layers "F.Cu" "F.Mask" "F.Paste")
			(net "P12V_AUX")
		)
		(pad "2" smd circle
			(at 0.40005 0 180)
			(size 0 0)
			(layers "F.Cu" "F.Mask" "F.Paste")
			(net "P12V_E1S_VCC_0")
		)
	)
)
